# S9S_MB_2U (Grand Teton) — schematic netlist excerpt (pin names and nets, part order shuffled) for the footprints in the layout excerpt that follows; sources: Cadence DE-HDL packaged netlist, KiCad conversion of 03242023_DA0F0TMBIJ0_F0T_Motherboard_J_brd_V01_OCP.brd

PC512_P1_5  Q_CAP  22UF 16V 20% X6S  pkg C0805  page 287 : A = SW_P12V_PVCCIN_CPU1_FLT ; B = GND
C39  Q_CAP  10UF 16V 10% X6S  pkg C0805  page 94 : A = P12V_S3_AUX_CPU0_NVDIMM ; B = GND
R296  Q_RES  301 1% CHIP  pkg 0402LF  page 118 : A = PVNN_TERM_CPU0 ; B = H_CPU_CATERR_LVC1_R_N

(kicad_pcb
	(version 20260206)
	(generator "pcbnew")
	(generator_version "10.0")
	(general
		(thickness 1.6)
		(legacy_teardrops no)
	)
	(paper "A4")
	(title_block
		(title "03242023_DA0F0TMBIJ0_F0T_Motherboard_J_brd_V01_OCP.brd")
		(comment 1 "Grand Teton / footprints 6092-6094 of 6105")
	)
	(layers
		(0 "F.Cu" signal "TOP")
		(4 "In1.Cu" signal "GND")
		(6 "In2.Cu" signal "IN1")
		(8 "In3.Cu" signal "GND1")
		(10 "In4.Cu" signal "IN2")
		(12 "In5.Cu" signal "GND2")
		(14 "In6.Cu" signal "IN3")
		(16 "In7.Cu" signal "GND3")
		(18 "In8.Cu" signal "VCC")
		(20 "In9.Cu" signal "VCC1")
		(22 "In10.Cu" signal "GND4")
		(24 "In11.Cu" signal "IN4")
		(26 "In12.Cu" signal "GND5")
		(28 "In13.Cu" signal "IN5")
		(30 "In14.Cu" signal "GND6")
		(32 "In15.Cu" signal "IN6")
		(34 "In16.Cu" signal "GND7")
		(2 "B.Cu" signal "BOTTOM")
		(9 "F.Adhes" user "F.Adhesive")
		(11 "B.Adhes" user "B.Adhesive")
		(13 "F.Paste" user "Package Geometry/Pastemask Top")
		(15 "B.Paste" user "Package Geometry/Pastemask Bottom")
		(5 "F.SilkS" user "Ref Des/Silkscreen Top")
		(7 "B.SilkS" user "Ref Des/Silkscreen Bottom")
		(1 "F.Mask" user "Board Geometry/Soldermask Top")
		(3 "B.Mask" user "Board Geometry/Soldermask Bottom")
		(17 "Dwgs.User" user "User.Drawings")
		(19 "Cmts.User" user "User.Comments")
		(21 "Eco1.User" user "User.Eco1")
		(23 "Eco2.User" user "User.Eco2")
		(25 "Edge.Cuts" user "Board Geometry/Outline")
		(27 "Margin" user)
		(31 "F.CrtYd" user "Package Geometry/Place Bound Top")
		(29 "B.CrtYd" user "Package Geometry/Place Bound Bottom")
		(35 "F.Fab" user "Ref Des/Assembly Top")
		(33 "B.Fab" user "Ref Des/Assembly Bottom")
	)
	(footprint ""
		(layer "B.Cu")
		(at 329.170538 -184.58815 -90)
		(property "Reference" "R296"
			(at 0 0 90)
			(layer "B.SilkS")
			(hide yes)
			(effects
				(font
					(size 1.27 1.27)
				)
				(justify mirror)
			)
		)
		(property "Value" ""
			(at 0 0 90)
			(layer "B.Fab")
			(effects
				(font
					(size 1.27 1.27)
				)
				(justify mirror)
			)
		)
		(duplicate_pad_numbers_are_jumpers no)
		(fp_line
			(start -0.7874 0.4064)
			(end 0.7874 0.4064)
			(stroke
				(width 0.1524)
				(type default)
			)
			(layer "B.SilkS")
		)
		(fp_line
			(start 0.7874 0.4064)
			(end 0.7874 -0.4064)
			(stroke
				(width 0.1524)
				(type default)
			)
			(layer "B.SilkS")
		)
		(fp_line
			(start -0.7874 -0.4064)
			(end -0.7874 0.4064)
			(stroke
				(width 0.1524)
				(type default)
			)
			(layer "B.SilkS")
		)
		(fp_line
			(start 0.7874 -0.4064)
			(end -0.7874 -0.4064)
			(stroke
				(width 0.1524)
				(type default)
			)
			(layer "B.SilkS")
		)
		(fp_line
			(start -0.67945 0.3048)
			(end -0.120396 0.3048)
			(stroke
				(width 0.1)
				(type default)
			)
			(layer "B.Fab")
		)
		(fp_line
			(start -0.120396 0.3048)
			(end -0.120396 0.2794)
			(stroke
				(width 0.1)
				(type default)
			)
			(layer "B.Fab")
		)
		(fp_line
			(start 0.12065 0.3048)
			(end 0.67945 0.3048)
			(stroke
				(width 0.1)
				(type default)
			)
			(layer "B.Fab")
		)
		(fp_line
			(start 0.67945 0.3048)
			(end 0.67945 -0.305054)
			(stroke
				(width 0.1)
				(type default)
			)
			(layer "B.Fab")
		)
		(fp_line
			(start -0.120396 0.2794)
			(end 0.12065 0.2794)
			(stroke
				(width 0.1)
				(type default)
			)
			(layer "B.Fab")
		)
		(fp_line
			(start 0.12065 0.2794)
			(end 0.12065 0.3048)
			(stroke
				(width 0.1)
				(type default)
			)
			(layer "B.Fab")
		)
		(fp_line
			(start -0.12065 -0.2794)
			(end -0.12065 -0.3048)
			(stroke
				(width 0.1)
				(type default)
			)
			(layer "B.Fab")
		)
		(fp_line
			(start 0.12065 -0.2794)
			(end -0.12065 -0.2794)
			(stroke
				(width 0.1)
				(type default)
			)
			(layer "B.Fab")
		)
		(fp_line
			(start -0.67945 -0.3048)
			(end -0.67945 0.3048)
			(stroke
				(width 0.1)
				(type default)
			)
			(layer "B.Fab")
		)
		(fp_line
			(start -0.12065 -0.3048)
			(end -0.67945 -0.3048)
			(stroke
				(width 0.1)
				(type default)
			)
			(layer "B.Fab")
		)
		(fp_line
			(start 0.12065 -0.305054)
			(end 0.12065 -0.2794)
			(stroke
				(width 0.1)
				(type default)
			)
			(layer "B.Fab")
		)
		(fp_line
			(start 0.67945 -0.305054)
			(end 0.12065 -0.305054)
			(stroke
				(width 0.1)
				(type default)
			)
			(layer "B.Fab")
		)
		(pad "1" smd circle
			(at 0.40005 0 90)
			(size 0 0)
			(layers "B.Cu" "B.Mask" "B.Paste")
			(net "PVNN_TERM_CPU0")
		)
		(pad "2" smd circle
			(at -0.40005 0 90)
			(size 0 0)
			(layers "B.Cu" "B.Mask" "B.Paste")
			(net "H_CPU_CATERR_LVC1_R_N")
		)
	)
	(footprint ""
		(layer "B.Cu")
		(at 130.761486 -337.145884 90)
		(property "Reference" "PC512_P1_5"
			(at 0 0 90)
			(layer "B.SilkS")
			(hide yes)
			(effects
				(font
					(size 1.27 1.27)
				)
				(justify mirror)
			)
		)
		(property "Value" ""
			(at 0 0 90)
			(layer "B.Fab")
			(effects
				(font
					(size 1.27 1.27)
				)
				(justify mirror)
			)
		)
		(duplicate_pad_numbers_are_jumpers no)
		(fp_line
			(start 1.524 -0.762)
			(end -1.524 -0.762)
			(stroke
				(width 0.1524)
				(type default)
			)
			(layer "B.SilkS")
		)
		(fp_line
			(start -1.524 -0.762)
			(end -1.524 0.762)
			(stroke
				(width 0.1524)
				(type default)
			)
			(layer "B.SilkS")
		)
		(fp_line
			(start 1.524 0.762)
			(end 1.524 -0.762)
			(stroke
				(width 0.1524)
				(type default)
			)
			(layer "B.SilkS")
		)
		(fp_line
			(start -1.524 0.762)
			(end 1.524 0.762)
			(stroke
				(width 0.1524)
				(type default)
			)
			(layer "B.SilkS")
		)
		(fp_line
			(start 1.1049 -0.724916)
			(end 1.1049 0.724916)
			(stroke
				(width 0.1)
				(type default)
			)
			(layer "B.Fab")
		)
		(fp_line
			(start -1.1049 -0.724916)
			(end 1.1049 -0.724916)
			(stroke
				(width 0.1)
				(type default)
			)
			(layer "B.Fab")
		)
		(fp_line
			(start 1.1049 0.724916)
			(end -1.1049 0.724916)
			(stroke
				(width 0.1)
				(type default)
			)
			(layer "B.Fab")
		)
		(fp_line
			(start -1.1049 0.724916)
			(end -1.1049 -0.724916)
			(stroke
				(width 0.1)
				(type default)
			)
			(layer "B.Fab")
		)
		(pad "1" smd rect
			(at 0.889 0 90)
			(size 1.016 1.27)
			(layers "B.Cu" "B.Mask" "B.Paste")
			(net "SW_P12V_PVCCIN_CPU1_FLT")
		)
		(pad "2" smd rect
			(at -0.889 0 90)
			(size 1.016 1.27)
			(layers "B.Cu" "B.Mask" "B.Paste")
			(net "GND")
		)
	)
	(footprint ""
		(layer "B.Cu")
		(at 448.549014 -321.549776 -90)
		(property "Reference" "C39"
			(at 0 0 90)
			(layer "B.SilkS")
			(hide yes)
			(effects
				(font
					(size 1.27 1.27)
				)
				(justify mirror)
			)
		)
		(property "Value" ""
			(at 0 0 90)
			(layer "B.Fab")
			(effects
				(font
					(size 1.27 1.27)
				)
				(justify mirror)
			)
		)
		(duplicate_pad_numbers_are_jumpers no)
		(fp_line
			(start -1.524 0.762)
			(end 1.524 0.762)
			(stroke
				(width 0.1524)
				(type default)
			)
			(layer "B.SilkS")
		)
		(fp_line
			(start 1.524 0.762)
			(end 1.524 -0.762)
			(stroke
				(width 0.1524)
				(type default)
			)
			(layer "B.SilkS")
		)
		(fp_line
			(start -1.524 -0.762)
			(end -1.524 0.762)
			(stroke
				(width 0.1524)
				(type default)
			)
			(layer "B.SilkS")
		)
		(fp_line
			(start 1.524 -0.762)
			(end -1.524 -0.762)
			(stroke
				(width 0.1524)
				(type default)
			)
			(layer "B.SilkS")
		)
		(fp_line
			(start -1.1049 0.724916)
			(end -1.1049 -0.724916)
			(stroke
				(width 0.1)
				(type default)
			)
			(layer "B.Fab")
		)
		(fp_line
			(start 1.1049 0.724916)
			(end -1.1049 0.724916)
			(stroke
				(width 0.1)
				(type default)
			)
			(layer "B.Fab")
		)
		(fp_line
			(start -1.1049 -0.724916)
			(end 1.1049 -0.724916)
			(stroke
				(width 0.1)
				(type default)
			)
			(layer "B.Fab")
		)
		(fp_line
			(start 1.1049 -0.724916)
			(end 1.1049 0.724916)
			(stroke
				(width 0.1)
				(type default)
			)
			(layer "B.Fab")
		)
		(pad "1" smd rect
			(at 0.889 0 270)
			(size 1.016 1.27)
			(layers "B.Cu" "B.Mask" "B.Paste")
			(net "P12V_S3_AUX_CPU0_NVDIMM")
		)
		(pad "2" smd rect
			(at -0.889 0 270)
			(size 1.016 1.27)
			(layers "B.Cu" "B.Mask" "B.Paste")
			(net "GND")
		)
	)
)
